(kicad_pcb
	(version 20260206)
	(generator "pcbnew")
	(generator_version "10.0")
	(general
		(thickness 1.6)
		(legacy_teardrops no)
	)
	(paper "A4")
	(title_block
		(title "pdpb — Lightning_PDPB_BRD.brd")
		(comment 1 "Lightning (Wiwynn / Facebook NVMe JBOF) / footprints 787-793 of 1140")
	)
	(layers
		(0 "F.Cu" signal "TOP")
		(4 "In1.Cu" signal "L2GND")
		(6 "In2.Cu" signal "L3")
		(8 "In3.Cu" signal "L4VCC")
		(10 "In4.Cu" signal "L5VCC")
		(12 "In5.Cu" signal "L6")
		(14 "In6.Cu" signal "L7GND")
		(2 "B.Cu" signal "BOTTOM")
		(9 "F.Adhes" user "F.Adhesive")
		(11 "B.Adhes" user "B.Adhesive")
		(13 "F.Paste" user "Package Geometry/Pastemask Top")
		(15 "B.Paste" user "Package Geometry/Pastemask Bottom")
		(5 "F.SilkS" user "Ref Des/Silkscreen Top")
		(7 "B.SilkS" user "Ref Des/Silkscreen Bottom")
		(1 "F.Mask" user "Board Geometry/Soldermask Top")
		(3 "B.Mask" user "Board Geometry/Soldermask Bottom")
		(17 "Dwgs.User" user "User.Drawings")
		(19 "Cmts.User" user "User.Comments")
		(21 "Eco1.User" user "User.Eco1")
		(23 "Eco2.User" user "User.Eco2")
		(25 "Edge.Cuts" user "Board Geometry/Outline")
		(27 "Margin" user)
		(31 "F.CrtYd" user "Package Geometry/Place Bound Top")
		(29 "B.CrtYd" user "Package Geometry/Place Bound Bottom")
		(35 "F.Fab" user "Ref Des/Assembly Top")
		(33 "B.Fab" user "Ref Des/Assembly Bottom")
	)
	(footprint ""
		(layer "F.Cu")
		(at 24.13 -397.891 180)
		(property "Reference" "Q14"
			(at 0 0 180)
			(layer "F.SilkS")
			(hide yes)
			(effects
				(font
					(size 1.27 1.27)
				)
			)
		)
		(property "Value" "2N7002A-7-GP"
			(at 0.127 -8.9662 180)
			(unlocked yes)
			(layer "F.Fab")
			(hide yes)
			(effects
				(font
					(size 1.016 1.016)
					(thickness 0.1524)
				)
			)
		)
		(property "Device Type" "SOT23DGS2D4H48"
			(at 0.127 -10.4902 180)
			(unlocked yes)
			(layer "F.Fab")
			(hide yes)
			(effects
				(font
					(size 1.016 1.016)
					(thickness 0.1524)
				)
			)
		)
		(duplicate_pad_numbers_are_jumpers no)
		(fp_line
			(start 1.651 1.778)
			(end 1.651 -1.778)
			(stroke
				(width 0.1524)
				(type default)
			)
			(layer "F.SilkS")
		)
		(fp_line
			(start 1.651 -1.778)
			(end -1.651 -1.778)
			(stroke
				(width 0.1524)
				(type default)
			)
			(layer "F.SilkS")
		)
		(fp_line
			(start -1.651 1.778)
			(end 1.651 1.778)
			(stroke
				(width 0.1524)
				(type default)
			)
			(layer "F.SilkS")
		)
		(fp_line
			(start -1.651 -1.778)
			(end -1.651 1.778)
			(stroke
				(width 0.1524)
				(type default)
			)
			(layer "F.SilkS")
		)
		(fp_poly
			(pts
				(xy -1.778 1.8796) (xy -1.778 -1.8796) (xy 1.778 -1.8796) (xy 1.778 1.8796)
			)
			(stroke
				(width 0)
				(type default)
			)
			(fill no)
			(layer "F.CrtYd")
		)
		(fp_poly
			(pts
				(xy -1.778 1.8796) (xy -1.778 -1.8796) (xy 1.778 -1.8796) (xy 1.778 1.8796)
			)
			(stroke
				(width 0)
				(type default)
			)
			(fill no)
			(layer "F.Fab")
		)
		(pad "D" smd custom
			(at 0 -0.9525 180)
			(size 0.1905 0.1905)
			(layers "F.Cu" "F.Mask" "F.Paste")
			(net "SW_SSD6_R")
			(options
				(clearance outline)
				(anchor circle)
			)
			(primitives
				(gr_poly
					(pts
						(arc
							(start -0.1778 0.5715)
							(mid -0.321484 0.511984)
							(end -0.381 0.3683)
						)
						(arc
							(start -0.381 -0.3683)
							(mid -0.321484 -0.511984)
							(end -0.1778 -0.5715)
						)
						(arc
							(start 0.1778 -0.5715)
							(mid 0.321484 -0.511984)
							(end 0.381 -0.3683)
						)
						(arc
							(start 0.381 0.3683)
							(mid 0.321484 0.511984)
							(end 0.1778 0.5715)
						)
					)
					(width 0)
					(fill yes)
				)
			)
		)
		(pad "G" smd custom
			(at -0.98425 0.9525 180)
			(size 0.1905 0.1905)
			(layers "F.Cu" "F.Mask" "F.Paste")
			(net "SSD6_PWREN")
			(options
				(clearance outline)
				(anchor circle)
			)
			(primitives
				(gr_poly
					(pts
						(arc
							(start -0.1778 0.5715)
							(mid -0.321484 0.511984)
							(end -0.381 0.3683)
						)
						(arc
							(start -0.381 -0.3683)
							(mid -0.321484 -0.511984)
							(end -0.1778 -0.5715)
						)
						(arc
							(start 0.1778 -0.5715)
							(mid 0.321484 -0.511984)
							(end 0.381 -0.3683)
						)
						(arc
							(start 0.381 0.3683)
							(mid 0.321484 0.511984)
							(end 0.1778 0.5715)
						)
					)
					(width 0)
					(fill yes)
				)
			)
		)
		(pad "S" smd custom
			(at 0.98425 0.9525 180)
			(size 0.1905 0.1905)
			(layers "F.Cu" "F.Mask" "F.Paste")
			(net "GND")
			(options
				(clearance outline)
				(anchor circle)
			)
			(primitives
				(gr_poly
					(pts
						(arc
							(start -0.1778 0.5715)
							(mid -0.321484 0.511984)
							(end -0.381 0.3683)
						)
						(arc
							(start -0.381 -0.3683)
							(mid -0.321484 -0.511984)
							(end -0.1778 -0.5715)
						)
						(arc
							(start 0.1778 -0.5715)
							(mid 0.321484 -0.511984)
							(end 0.381 -0.3683)
						)
						(arc
							(start 0.381 0.3683)
							(mid 0.321484 0.511984)
							(end 0.1778 0.5715)
						)
					)
					(width 0)
					(fill yes)
				)
			)
		)
	)
	(footprint ""
		(layer "F.Cu")
		(at 18.50009 -361.899962)
		(property "Reference" "LED11"
			(at 0 0 0)
			(layer "F.SilkS")
			(hide yes)
			(effects
				(font
					(size 1.27 1.27)
				)
			)
		)
		(property "Value" "LED-RB-4-GP"
			(at 5.88899 1.80848 0)
			(unlocked yes)
			(layer "F.Fab")
			(hide yes)
			(effects
				(font
					(size 1.016 1.016)
					(thickness 0.1524)
				)
			)
		)
		(property "Device Type" "LED1613-4PH20"
			(at 5.88899 0.28448 0)
			(unlocked yes)
			(layer "F.Fab")
			(hide yes)
			(effects
				(font
					(size 1.016 1.016)
					(thickness 0.1524)
				)
			)
		)
		(duplicate_pad_numbers_are_jumpers no)
		(fp_line
			(start -1.4478 -0.9652)
			(end 1.4478 -0.9652)
			(stroke
				(width 0.1524)
				(type default)
			)
			(layer "F.SilkS")
		)
		(fp_line
			(start -1.4478 0.9652)
			(end -1.4478 -0.9652)
			(stroke
				(width 0.1524)
				(type default)
			)
			(layer "F.SilkS")
		)
		(fp_line
			(start -1.4478 0.9652)
			(end -1.4478 -0.9652)
			(stroke
				(width 0.508)
				(type default)
			)
			(layer "F.SilkS")
		)
		(fp_line
			(start 1.4478 -0.9652)
			(end 1.4478 0.9652)
			(stroke
				(width 0.1524)
				(type default)
			)
			(layer "F.SilkS")
		)
		(fp_line
			(start 1.4478 0.9652)
			(end -1.4478 0.9652)
			(stroke
				(width 0.1524)
				(type default)
			)
			(layer "F.SilkS")
		)
		(fp_rect
			(start -0.8001 0.6477)
			(end 0.8001 -0.6477)
			(stroke
				(width 0)
				(type default)
			)
			(fill no)
			(layer "F.CrtYd")
		)
		(fp_poly
			(pts
				(xy -1.7018 1.2192) (xy -1.7018 -0.06223) (xy -0.8001 -0.06223) (xy -0.8001 0.6477) (xy 0.8001 0.6477)
				(xy 0.8001 -0.6477) (xy -0.8001 -0.6477) (xy -0.8001 -0.0635) (xy -1.7018 -0.0635) (xy -1.7018 -1.2192)
				(xy 1.7018 -1.2192) (xy 1.7018 1.2192)
			)
			(stroke
				(width 0)
				(type default)
			)
			(fill no)
			(layer "F.CrtYd")
		)
		(fp_rect
			(start -1.7018 1.2192)
			(end 1.7018 -1.2192)
			(stroke
				(width 0)
				(type default)
			)
			(fill no)
			(layer "F.Fab")
		)
		(pad "1" smd rect
			(at -0.73025 0.4064)
			(size 0.9144 0.6096)
			(layers "F.Cu" "F.Mask" "F.Paste")
			(net "SSD_ACT_DR11_MOS_N")
		)
		(pad "2" smd rect
			(at -0.73025 -0.4064)
			(size 0.9144 0.6096)
			(layers "F.Cu" "F.Mask" "F.Paste")
			(net "ATTN_LED_DR11_MOS_N")
		)
		(pad "3" smd rect
			(at 0.73025 -0.4064)
			(size 0.9144 0.6096)
			(layers "F.Cu" "F.Mask" "F.Paste")
			(net "DRV_ATTN_11")
		)
		(pad "4" smd rect
			(at 0.73025 0.4064)
			(size 0.9144 0.6096)
			(layers "F.Cu" "F.Mask" "F.Paste")
			(net "DRV_ACT_11")
		)
	)
	(footprint ""
		(layer "F.Cu")
		(at 19.5072 -103.4288 180)
		(property "Reference" "R9246"
			(at 0 0 180)
			(layer "F.SilkS")
			(hide yes)
			(effects
				(font
					(size 1.27 1.27)
				)
			)
		)
		(property "Value" "2R2010F-GP"
			(at 0.0762 -4.5466 180)
			(unlocked yes)
			(layer "F.Fab")
			(hide yes)
			(effects
				(font
					(size 1.016 1.016)
					(thickness 0.1524)
				)
			)
		)
		(property "Device Type" "R2010H26"
			(at 0.0762 -6.1468 180)
			(unlocked yes)
			(layer "F.Fab")
			(hide yes)
			(effects
				(font
					(size 1.016 1.016)
					(thickness 0.1524)
				)
			)
		)
		(duplicate_pad_numbers_are_jumpers no)
		(fp_line
			(start 3.302 1.651)
			(end 3.302 -1.651)
			(stroke
				(width 0.1524)
				(type default)
			)
			(layer "F.SilkS")
		)
		(fp_line
			(start 3.302 -1.651)
			(end -3.302 -1.651)
			(stroke
				(width 0.1524)
				(type default)
			)
			(layer "F.SilkS")
		)
		(fp_line
			(start -3.302 1.651)
			(end 3.302 1.651)
			(stroke
				(width 0.1524)
				(type default)
			)
			(layer "F.SilkS")
		)
		(fp_line
			(start -3.302 -1.651)
			(end -3.302 1.651)
			(stroke
				(width 0.1524)
				(type default)
			)
			(layer "F.SilkS")
		)
		(fp_rect
			(start -3.3782 1.7272)
			(end 3.3782 -1.7272)
			(stroke
				(width 0)
				(type default)
			)
			(fill no)
			(layer "F.CrtYd")
		)
		(fp_poly
			(pts
				(xy 3.3782 -1.7272) (xy -3.3782 -1.7272) (xy -3.3782 1.7272) (xy 3.3782 1.7272)
			)
			(stroke
				(width 0)
				(type default)
			)
			(fill no)
			(layer "F.Fab")
		)
		(pad "1" smd rect
			(at -2.3495 0 180)
			(size 1.143 2.794)
			(layers "F.Cu" "F.Mask" "F.Paste")
			(net "P12V_SSD13")
		)
		(pad "2" smd rect
			(at 2.3495 0 180)
			(size 1.143 2.794)
			(layers "F.Cu" "F.Mask" "F.Paste")
			(net "12V_PRECH_SSD13")
		)
	)
	(footprint ""
		(layer "F.Cu")
		(at 35.4584 -13.6652 180)
		(property "Reference" "PC1230"
			(at 0 0 180)
			(layer "F.SilkS")
			(hide yes)
			(effects
				(font
					(size 1.27 1.27)
				)
			)
		)
		(property "Value" "SC22U25V6KX-GP-U"
			(at -2.860802 -5.279644 180)
			(unlocked yes)
			(layer "F.Fab")
			(hide yes)
			(effects
				(font
					(size 1.016 1.016)
					(thickness 0.1524)
				)
			)
		)
		(property "Device Type" "C1206-TO0D3H75"
			(at -2.860802 -6.803644 180)
			(unlocked yes)
			(layer "F.Fab")
			(hide yes)
			(effects
				(font
					(size 1.016 1.016)
					(thickness 0.1524)
				)
			)
		)
		(duplicate_pad_numbers_are_jumpers no)
		(fp_line
			(start 1.3081 2.3749)
			(end -1.3081 2.3749)
			(stroke
				(width 0.1524)
				(type default)
			)
			(layer "F.SilkS")
		)
		(fp_line
			(start 1.3081 -2.3749)
			(end 1.3081 2.3749)
			(stroke
				(width 0.1524)
				(type default)
			)
			(layer "F.SilkS")
		)
		(fp_line
			(start -1.3081 2.3749)
			(end -1.3081 -2.3749)
			(stroke
				(width 0.1524)
				(type default)
			)
			(layer "F.SilkS")
		)
		(fp_line
			(start -1.3081 -2.3749)
			(end 1.3081 -2.3749)
			(stroke
				(width 0.1524)
				(type default)
			)
			(layer "F.SilkS")
		)
		(fp_rect
			(start -0.8001 1.6002)
			(end 0.8001 -1.6002)
			(stroke
				(width 0)
				(type default)
			)
			(fill no)
			(layer "F.CrtYd")
		)
		(fp_poly
			(pts
				(xy -1.5621 2.4511) (xy -1.5621 1.6002) (xy 0.8001 1.6002) (xy 0.8001 -1.6002) (xy -0.8001 -1.6002)
				(xy -0.8001 1.5875) (xy -1.5621 1.5875) (xy -1.5621 -2.4511) (xy 1.5621 -2.4511) (xy 1.5621 2.4511)
			)
			(stroke
				(width 0)
				(type default)
			)
			(fill no)
			(layer "F.CrtYd")
		)
		(fp_rect
			(start -1.5621 2.4511)
			(end 1.5621 -2.4511)
			(stroke
				(width 0)
				(type default)
			)
			(fill no)
			(layer "F.Fab")
		)
		(pad "1" smd rect
			(at 0 -1.392936 180)
			(size 2.1082 1.4478)
			(layers "F.Cu" "F.Mask" "F.Paste")
			(net "P12V_SSD14")
		)
		(pad "2" smd rect
			(at 0 1.392936 180)
			(size 2.1082 1.4478)
			(layers "F.Cu" "F.Mask" "F.Paste")
			(net "GND")
		)
	)
	(footprint ""
		(layer "F.Cu")
		(at 31.369 -300.9646 -90)
		(property "Reference" "Q61"
			(at 0 0 270)
			(layer "F.SilkS")
			(hide yes)
			(effects
				(font
					(size 1.27 1.27)
				)
			)
		)
		(property "Value" "2N7002A-7-GP"
			(at 0.127 -8.9662 270)
			(unlocked yes)
			(layer "F.Fab")
			(hide yes)
			(effects
				(font
					(size 1.016 1.016)
					(thickness 0.1524)
				)
			)
		)
		(property "Device Type" "SOT23DGS2D4H48"
			(at 0.127 -10.4902 270)
			(unlocked yes)
			(layer "F.Fab")
			(hide yes)
			(effects
				(font
					(size 1.016 1.016)
					(thickness 0.1524)
				)
			)
		)
		(duplicate_pad_numbers_are_jumpers no)
		(fp_line
			(start -1.651 1.778)
			(end 1.651 1.778)
			(stroke
				(width 0.1524)
				(type default)
			)
			(layer "F.SilkS")
		)
		(fp_line
			(start 1.651 1.778)
			(end 1.651 -1.778)
			(stroke
				(width 0.1524)
				(type default)
			)
			(layer "F.SilkS")
		)
		(fp_line
			(start -1.651 -1.778)
			(end -1.651 1.778)
			(stroke
				(width 0.1524)
				(type default)
			)
			(layer "F.SilkS")
		)
		(fp_line
			(start 1.651 -1.778)
			(end -1.651 -1.778)
			(stroke
				(width 0.1524)
				(type default)
			)
			(layer "F.SilkS")
		)
		(fp_poly
			(pts
				(xy -1.778 1.8796) (xy -1.778 -1.8796) (xy 1.778 -1.8796) (xy 1.778 1.8796)
			)
			(stroke
				(width 0)
				(type default)
			)
			(fill no)
			(layer "F.CrtYd")
		)
		(fp_poly
			(pts
				(xy -1.778 1.8796) (xy -1.778 -1.8796) (xy 1.778 -1.8796) (xy 1.778 1.8796)
			)
			(stroke
				(width 0)
				(type default)
			)
			(fill no)
			(layer "F.Fab")
		)
		(pad "D" smd custom
			(at 0 -0.9525 270)
			(size 0.1905 0.1905)
			(layers "F.Cu" "F.Mask" "F.Paste")
			(net "P12V_MOST7_GATE_D")
			(options
				(clearance outline)
				(anchor circle)
			)
			(primitives
				(gr_poly
					(pts
						(arc
							(start -0.1778 0.5715)
							(mid -0.321484 0.511984)
							(end -0.381 0.3683)
						)
						(arc
							(start -0.381 -0.3683)
							(mid -0.321484 -0.511984)
							(end -0.1778 -0.5715)
						)
						(arc
							(start 0.1778 -0.5715)
							(mid 0.321484 -0.511984)
							(end 0.381 -0.3683)
						)
						(arc
							(start 0.381 0.3683)
							(mid 0.321484 0.511984)
							(end 0.1778 0.5715)
						)
					)
					(width 0)
					(fill yes)
				)
			)
		)
		(pad "G" smd custom
			(at -0.98425 0.9525 270)
			(size 0.1905 0.1905)
			(layers "F.Cu" "F.Mask" "F.Paste")
			(net "P12V_MOST7_GATE")
			(options
				(clearance outline)
				(anchor circle)
			)
			(primitives
				(gr_poly
					(pts
						(arc
							(start -0.1778 0.5715)
							(mid -0.321484 0.511984)
							(end -0.381 0.3683)
						)
						(arc
							(start -0.381 -0.3683)
							(mid -0.321484 -0.511984)
							(end -0.1778 -0.5715)
						)
						(arc
							(start 0.1778 -0.5715)
							(mid 0.321484 -0.511984)
							(end 0.381 -0.3683)
						)
						(arc
							(start 0.381 0.3683)
							(mid 0.321484 0.511984)
							(end 0.1778 0.5715)
						)
					)
					(width 0)
					(fill yes)
				)
			)
		)
		(pad "S" smd custom
			(at 0.98425 0.9525 270)
			(size 0.1905 0.1905)
			(layers "F.Cu" "F.Mask" "F.Paste")
			(net "GND")
			(options
				(clearance outline)
				(anchor circle)
			)
			(primitives
				(gr_poly
					(pts
						(arc
							(start -0.1778 0.5715)
							(mid -0.321484 0.511984)
							(end -0.381 0.3683)
						)
						(arc
							(start -0.381 -0.3683)
							(mid -0.321484 -0.511984)
							(end -0.1778 -0.5715)
						)
						(arc
							(start 0.1778 -0.5715)
							(mid 0.321484 -0.511984)
							(end 0.381 -0.3683)
						)
						(arc
							(start 0.381 0.3683)
							(mid 0.321484 0.511984)
							(end 0.1778 0.5715)
						)
					)
					(width 0)
					(fill yes)
				)
			)
		)
	)
	(footprint ""
		(layer "F.Cu")
		(at 32.95015 -402.57095)
		(property "Reference" "R9818"
			(at 0 0 0)
			(layer "F.SilkS")
			(hide yes)
			(effects
				(font
					(size 1.27 1.27)
				)
			)
		)
		(property "Value" "2K2R5F-GP"
			(at 0 -8.9535 0)
			(unlocked yes)
			(layer "F.Fab")
			(hide yes)
			(effects
				(font
					(size 1.27 1.016)
					(thickness 0.1524)
				)
			)
		)
		(property "Device Type" "R805H24"
			(at 0 -10.6299 0)
			(unlocked yes)
			(layer "F.Fab")
			(hide yes)
			(effects
				(font
					(size 1.27 1.016)
					(thickness 0.1524)
				)
			)
		)
		(duplicate_pad_numbers_are_jumpers no)
		(fp_line
			(start -0.889 -1.7018)
			(end -0.889 0.2794)
			(stroke
				(width 0.1524)
				(type default)
			)
			(layer "F.SilkS")
		)
		(fp_line
			(start -0.889 0.0762)
			(end -0.889 1.7018)
			(stroke
				(width 0.1524)
				(type default)
			)
			(layer "F.SilkS")
		)
		(fp_line
			(start -0.889 1.7018)
			(end 0.889 1.7018)
			(stroke
				(width 0.1524)
				(type default)
			)
			(layer "F.SilkS")
		)
		(fp_line
			(start 0.889 -1.7018)
			(end -0.889 -1.7018)
			(stroke
				(width 0.1524)
				(type default)
			)
			(layer "F.SilkS")
		)
		(fp_line
			(start 0.889 -1.7018)
			(end 0.889 -0.381)
			(stroke
				(width 0.1524)
				(type default)
			)
			(layer "F.SilkS")
		)
		(fp_line
			(start 0.889 1.7018)
			(end 0.889 -0.508)
			(stroke
				(width 0.1524)
				(type default)
			)
			(layer "F.SilkS")
		)
		(fp_poly
			(pts
				(xy 0.9652 -1.778) (xy 0.9652 1.778) (xy -0.9652 1.778) (xy -0.9652 -1.778)
			)
			(stroke
				(width 0)
				(type default)
			)
			(fill no)
			(layer "F.CrtYd")
		)
		(fp_rect
			(start -0.9652 1.778)
			(end 0.9652 -1.778)
			(stroke
				(width 0)
				(type default)
			)
			(fill no)
			(layer "F.Fab")
		)
		(pad "1" smd rect
			(at 0 -0.9652)
			(size 1.397 1.143)
			(layers "F.Cu" "F.Mask" "F.Paste")
			(net "P12V_SSD6")
		)
		(pad "2" smd rect
			(at 0 0.9652)
			(size 1.397 1.143)
			(layers "F.Cu" "F.Mask" "F.Paste")
			(net "P12V_MOST6_GATE_D")
		)
	)
	(footprint ""
		(layer "F.Cu")
		(at 217.043 -185.801 -90)
		(property "Reference" "R394"
			(at 0 0 270)
			(layer "F.SilkS")
			(hide yes)
			(effects
				(font
					(size 1.27 1.27)
				)
			)
		)
		(property "Value" "0R2J-2-GP"
			(at 0.064008 -3.993896 270)
			(unlocked yes)
			(layer "F.Fab")
			(hide yes)
			(effects
				(font
					(size 1.016 1.016)
					(thickness 0.1524)
				)
			)
		)
		(property "Device Type" "R402H16"
			(at 0.064008 -5.517896 270)
			(unlocked yes)
			(layer "F.Fab")
			(hide yes)
			(effects
				(font
					(size 1.016 1.016)
					(thickness 0.1524)
				)
			)
		)
		(duplicate_pad_numbers_are_jumpers no)
		(fp_line
			(start -0.508 -0.9398)
			(end -0.508 0.9398)
			(stroke
				(width 0.1524)
				(type default)
			)
			(layer "F.SilkS")
		)
		(fp_line
			(start 0.508 -0.9398)
			(end -0.508 -0.9398)
			(stroke
				(width 0.1524)
				(type default)
			)
			(layer "F.SilkS")
		)
		(fp_rect
			(start -0.508 0.9398)
			(end 0.508 -0.9398)
			(stroke
				(width 0)
				(type default)
			)
			(fill no)
			(layer "F.CrtYd")
		)
		(fp_rect
			(start -0.508 0.9398)
			(end 0.508 -0.9398)
			(stroke
				(width 0)
				(type default)
			)
			(fill no)
			(layer "F.Fab")
		)
		(pad "1" smd custom
			(at 0 -0.4445 270)
			(size 0.1397 0.1397)
			(layers "F.Cu" "F.Mask" "F.Paste")
			(net "SDA_DR3_R")
			(options
				(clearance outline)
				(anchor circle)
			)
			(primitives
				(gr_poly
					(pts
						(arc
							(start -0.1778 -0.2794)
							(mid -0.249642 -0.249642)
							(end -0.2794 -0.1778)
						)
						(arc
							(start -0.2794 0.1778)
							(mid -0.249642 0.249642)
							(end -0.1778 0.2794)
						)
						(arc
							(start 0.1778 0.2794)
							(mid 0.249642 0.249642)
							(end 0.2794 0.1778)
						)
						(arc
							(start 0.2794 -0.1778)
							(mid 0.249642 -0.249642)
							(end 0.1778 -0.2794)
						)
					)
					(width 0)
					(fill yes)
				)
			)
		)
		(pad "2" smd custom
			(at 0 0.4445 270)
			(size 0.1397 0.1397)
			(layers "F.Cu" "F.Mask" "F.Paste")
			(net "SDA_DR3")
			(options
				(clearance outline)
				(anchor circle)
			)
			(primitives
				(gr_poly
					(pts
						(arc
							(start -0.1778 -0.2794)
							(mid -0.249642 -0.249642)
							(end -0.2794 -0.1778)
						)
						(arc
							(start -0.2794 0.1778)
							(mid -0.249642 0.249642)
							(end -0.1778 0.2794)
						)
						(arc
							(start 0.1778 0.2794)
							(mid 0.249642 0.249642)
							(end 0.2794 0.1778)
						)
						(arc
							(start 0.2794 -0.1778)
							(mid 0.249642 -0.249642)
							(end 0.1778 -0.2794)
						)
					)
					(width 0)
					(fill yes)
				)
			)
		)
	)
)
